(kicad_pcb
	(version 20260206)
	(generator "pcbnew")
	(generator_version "10.0")
	(general
		(thickness 1.6)
		(legacy_teardrops no)
	)
	(paper "A4")
	(title_block
		(title "Bryce Canyon_SCC_16316-1_OCP.brd")
		(comment 1 "Bryce Canyon / footprint 482 of 1561 (U2), pads 355-477 of 896")
	)
	(layers
		(0 "F.Cu" signal "TOP")
		(4 "In1.Cu" signal "L2GND")
		(6 "In2.Cu" signal "L3")
		(8 "In3.Cu" signal "L4VCC")
		(10 "In4.Cu" signal "L5VCC")
		(12 "In5.Cu" signal "L6")
		(14 "In6.Cu" signal "L7GND")
		(2 "B.Cu" signal "BOTTOM")
		(9 "F.Adhes" user "F.Adhesive")
		(11 "B.Adhes" user "B.Adhesive")
		(13 "F.Paste" user "Package Geometry/Pastemask Top")
		(15 "B.Paste" user "Package Geometry/Pastemask Bottom")
		(5 "F.SilkS" user "Ref Des/Silkscreen Top")
		(7 "B.SilkS" user "Ref Des/Silkscreen Bottom")
		(1 "F.Mask" user "Board Geometry/Soldermask Top")
		(3 "B.Mask" user "Board Geometry/Soldermask Bottom")
		(17 "Dwgs.User" user "User.Drawings")
		(19 "Cmts.User" user "User.Comments")
		(21 "Eco1.User" user "User.Eco1")
		(23 "Eco2.User" user "User.Eco2")
		(25 "Edge.Cuts" user "Board Geometry/Outline")
		(27 "Margin" user)
		(31 "F.CrtYd" user "Package Geometry/Place Bound Top")
		(29 "B.CrtYd" user "Package Geometry/Place Bound Bottom")
		(35 "F.Fab" user "Ref Des/Assembly Top")
		(33 "B.Fab" user "Ref Des/Assembly Bottom")
	)
	(footprint ""
		(layer "F.Cu")
		(at 174.999904 -39.99992)
		(property "Reference" "U2"
			(at 0 0 0)
			(layer "F.SilkS")
			(hide yes)
			(effects
				(font
					(size 1.27 1.27)
				)
			)
		)
		(property "Value" "SAS3008C0-1-DB-500020657-1-GP"
			(at -20.374102 -5.0292 0)
			(unlocked yes)
			(layer "F.Fab")
			(hide yes)
			(effects
				(font
					(size 1.016 1.016)
					(thickness 0.1524)
				)
			)
		)
		(property "Device Type" "BGA896D25H78"
			(at -20.374102 -6.5532 0)
			(unlocked yes)
			(layer "F.Fab")
			(hide yes)
			(effects
				(font
					(size 1.016 1.016)
					(thickness 0.1524)
				)
			)
		)
		(duplicate_pad_numbers_are_jumpers no)
		(pad "B29" smd circle
			(at 10.80008 -10.80008)
			(size 0.4064 0.4064)
			(layers "F.Cu" "F.Mask" "F.Paste")
			(net "XM_ADDR_8")
		)
		(pad "B30" smd circle
			(at 11.599926 -10.80008)
			(size 0.4064 0.4064)
			(layers "F.Cu" "F.Mask" "F.Paste")
			(net "XM_ADDR_7")
		)
		(pad "C1" smd circle
			(at -11.599926 -9.99998)
			(size 0.4064 0.4064)
			(layers "F.Cu" "F.Mask" "F.Paste")
			(net "GND")
		)
		(pad "C2" smd circle
			(at -10.80008 -9.99998)
			(size 0.4064 0.4064)
			(layers "F.Cu" "F.Mask" "F.Paste")
			(net "Net_1166")
		)
		(pad "C3" smd circle
			(at -9.99998 -9.99998)
			(size 0.4064 0.4064)
			(layers "F.Cu" "F.Mask" "F.Paste")
			(net "Net_1167")
		)
		(pad "C4" smd circle
			(at -9.19988 -9.99998)
			(size 0.3556 0.3556)
			(layers "F.Cu" "F.Mask" "F.Paste")
			(net "Net_1168")
		)
		(pad "C5" smd circle
			(at -8.400034 -9.99998)
			(size 0.3556 0.3556)
			(layers "F.Cu" "F.Mask" "F.Paste")
			(net "GND")
		)
		(pad "C6" smd circle
			(at -7.599934 -9.99998)
			(size 0.3556 0.3556)
			(layers "F.Cu" "F.Mask" "F.Paste")
			(net "ICE1_TRST#")
		)
		(pad "C7" smd circle
			(at -6.800088 -9.99998)
			(size 0.3556 0.3556)
			(layers "F.Cu" "F.Mask" "F.Paste")
			(net "ICE0_TMS")
		)
		(pad "C8" smd circle
			(at -5.999988 -9.99998)
			(size 0.3556 0.3556)
			(layers "F.Cu" "F.Mask" "F.Paste")
			(net "ICE0_TDO")
		)
		(pad "C9" smd circle
			(at -5.199888 -9.99998)
			(size 0.3556 0.3556)
			(layers "F.Cu" "F.Mask" "F.Paste")
			(net "Net_1169")
		)
		(pad "C10" smd circle
			(at -4.400042 -9.99998)
			(size 0.3556 0.3556)
			(layers "F.Cu" "F.Mask" "F.Paste")
			(net "Net_1170")
		)
		(pad "C11" smd circle
			(at -3.599942 -9.99998)
			(size 0.3556 0.3556)
			(layers "F.Cu" "F.Mask" "F.Paste")
			(net "GND")
		)
		(pad "C12" smd circle
			(at -2.800096 -9.99998)
			(size 0.3556 0.3556)
			(layers "F.Cu" "F.Mask" "F.Paste")
			(net "P1V8_C_PG_LS")
		)
		(pad "C13" smd circle
			(at -1.999996 -9.99998)
			(size 0.3556 0.3556)
			(layers "F.Cu" "F.Mask" "F.Paste")
			(net "Net_1154")
		)
		(pad "C14" smd circle
			(at -1.199896 -9.99998)
			(size 0.3556 0.3556)
			(layers "F.Cu" "F.Mask" "F.Paste")
			(net "GND")
		)
		(pad "C15" smd circle
			(at -0.40005 -9.99998)
			(size 0.3556 0.3556)
			(layers "F.Cu" "F.Mask" "F.Paste")
			(net "GND")
		)
		(pad "C16" smd circle
			(at 0.40005 -9.99998)
			(size 0.3556 0.3556)
			(layers "F.Cu" "F.Mask" "F.Paste")
			(net "LSI_TN")
		)
		(pad "C17" smd circle
			(at 1.199896 -9.99998)
			(size 0.3556 0.3556)
			(layers "F.Cu" "F.Mask" "F.Paste")
			(net "JTAG_IOC_TCK")
		)
		(pad "C18" smd circle
			(at 1.999996 -9.99998)
			(size 0.3556 0.3556)
			(layers "F.Cu" "F.Mask" "F.Paste")
			(net "IOC_TDO")
		)
		(pad "C19" smd circle
			(at 2.800096 -9.99998)
			(size 0.3556 0.3556)
			(layers "F.Cu" "F.Mask" "F.Paste")
			(net "XM_DATA_15")
		)
		(pad "C20" smd circle
			(at 3.599942 -9.99998)
			(size 0.3556 0.3556)
			(layers "F.Cu" "F.Mask" "F.Paste")
			(net "XM_DATA_6")
		)
		(pad "C21" smd circle
			(at 4.400042 -9.99998)
			(size 0.3556 0.3556)
			(layers "F.Cu" "F.Mask" "F.Paste")
			(net "XM_DATA_8")
		)
		(pad "C22" smd circle
			(at 5.199888 -9.99998)
			(size 0.3556 0.3556)
			(layers "F.Cu" "F.Mask" "F.Paste")
			(net "XM_DATA_5")
		)
		(pad "C23" smd circle
			(at 5.999988 -9.99998)
			(size 0.3556 0.3556)
			(layers "F.Cu" "F.Mask" "F.Paste")
			(net "XM_CLE")
		)
		(pad "C24" smd circle
			(at 6.800088 -9.99998)
			(size 0.3556 0.3556)
			(layers "F.Cu" "F.Mask" "F.Paste")
			(net "XM_DATA_7")
		)
		(pad "C25" smd circle
			(at 7.599934 -9.99998)
			(size 0.3556 0.3556)
			(layers "F.Cu" "F.Mask" "F.Paste")
			(net "XM_DATA_10")
		)
		(pad "C26" smd circle
			(at 8.400034 -9.99998)
			(size 0.3556 0.3556)
			(layers "F.Cu" "F.Mask" "F.Paste")
			(net "XM_DATA_9")
		)
		(pad "C27" smd circle
			(at 9.19988 -9.99998)
			(size 0.3556 0.3556)
			(layers "F.Cu" "F.Mask" "F.Paste")
			(net "XM_ADDR_2")
		)
		(pad "C28" smd circle
			(at 9.99998 -9.99998)
			(size 0.4064 0.4064)
			(layers "F.Cu" "F.Mask" "F.Paste")
			(net "XM_ADDR_5")
		)
		(pad "C29" smd circle
			(at 10.80008 -9.99998)
			(size 0.4064 0.4064)
			(layers "F.Cu" "F.Mask" "F.Paste")
			(net "XM_ADDR_11")
		)
		(pad "C30" smd circle
			(at 11.599926 -9.99998)
			(size 0.4064 0.4064)
			(layers "F.Cu" "F.Mask" "F.Paste")
			(net "XM_ADDR_13")
		)
		(pad "D1" smd circle
			(at -11.599926 -9.19988)
			(size 0.3556 0.3556)
			(layers "F.Cu" "F.Mask" "F.Paste")
			(net "Net_1197")
		)
		(pad "D2" smd circle
			(at -10.80008 -9.19988)
			(size 0.3556 0.3556)
			(layers "F.Cu" "F.Mask" "F.Paste")
			(net "Net_1171")
		)
		(pad "D3" smd circle
			(at -9.99998 -9.19988)
			(size 0.3556 0.3556)
			(layers "F.Cu" "F.Mask" "F.Paste")
			(net "Net_1172")
		)
		(pad "D4" smd circle
			(at -9.19988 -9.19988)
			(size 0.3556 0.3556)
			(layers "F.Cu" "F.Mask" "F.Paste")
			(net "P1V8_C")
		)
		(pad "D5" smd circle
			(at -8.400034 -9.19988)
			(size 0.3556 0.3556)
			(layers "F.Cu" "F.Mask" "F.Paste")
			(net "GND")
		)
		(pad "D6" smd circle
			(at -7.599934 -9.19988)
			(size 0.3556 0.3556)
			(layers "F.Cu" "F.Mask" "F.Paste")
			(net "P1V8_C")
		)
		(pad "D7" smd circle
			(at -6.800088 -9.19988)
			(size 0.3556 0.3556)
			(layers "F.Cu" "F.Mask" "F.Paste")
			(net "GND")
		)
		(pad "D8" smd circle
			(at -5.999988 -9.19988)
			(size 0.3556 0.3556)
			(layers "F.Cu" "F.Mask" "F.Paste")
			(net "P1V8_C")
		)
		(pad "D9" smd circle
			(at -5.199888 -9.19988)
			(size 0.3556 0.3556)
			(layers "F.Cu" "F.Mask" "F.Paste")
			(net "GND")
		)
		(pad "D10" smd circle
			(at -4.400042 -9.19988)
			(size 0.3556 0.3556)
			(layers "F.Cu" "F.Mask" "F.Paste")
			(net "P1V8_C")
		)
		(pad "D11" smd circle
			(at -3.599942 -9.19988)
			(size 0.3556 0.3556)
			(layers "F.Cu" "F.Mask" "F.Paste")
			(net "GND")
		)
		(pad "D12" smd circle
			(at -2.800096 -9.19988)
			(size 0.3556 0.3556)
			(layers "F.Cu" "F.Mask" "F.Paste")
			(net "GND")
		)
		(pad "D13" smd circle
			(at -1.999996 -9.19988)
			(size 0.3556 0.3556)
			(layers "F.Cu" "F.Mask" "F.Paste")
			(net "GND")
		)
		(pad "D14" smd circle
			(at -1.199896 -9.19988)
			(size 0.3556 0.3556)
			(layers "F.Cu" "F.Mask" "F.Paste")
			(net "GND")
		)
		(pad "D15" smd circle
			(at -0.40005 -9.19988)
			(size 0.3556 0.3556)
			(layers "F.Cu" "F.Mask" "F.Paste")
			(net "GND")
		)
		(pad "D16" smd circle
			(at 0.40005 -9.19988)
			(size 0.3556 0.3556)
			(layers "F.Cu" "F.Mask" "F.Paste")
			(net "P1V8_C")
		)
		(pad "D17" smd circle
			(at 1.199896 -9.19988)
			(size 0.3556 0.3556)
			(layers "F.Cu" "F.Mask" "F.Paste")
			(net "GND")
		)
		(pad "D18" smd circle
			(at 1.999996 -9.19988)
			(size 0.3556 0.3556)
			(layers "F.Cu" "F.Mask" "F.Paste")
			(net "P1V8_C")
		)
		(pad "D19" smd circle
			(at 2.800096 -9.19988)
			(size 0.3556 0.3556)
			(layers "F.Cu" "F.Mask" "F.Paste")
			(net "GND")
		)
		(pad "D20" smd circle
			(at 3.599942 -9.19988)
			(size 0.3556 0.3556)
			(layers "F.Cu" "F.Mask" "F.Paste")
			(net "P1V8_C")
		)
		(pad "D21" smd circle
			(at 4.400042 -9.19988)
			(size 0.3556 0.3556)
			(layers "F.Cu" "F.Mask" "F.Paste")
			(net "GND")
		)
		(pad "D22" smd circle
			(at 5.199888 -9.19988)
			(size 0.3556 0.3556)
			(layers "F.Cu" "F.Mask" "F.Paste")
			(net "P1V8_C")
		)
		(pad "D23" smd circle
			(at 5.999988 -9.19988)
			(size 0.3556 0.3556)
			(layers "F.Cu" "F.Mask" "F.Paste")
			(net "GND")
		)
		(pad "D24" smd circle
			(at 6.800088 -9.19988)
			(size 0.3556 0.3556)
			(layers "F.Cu" "F.Mask" "F.Paste")
			(net "P1V8_C")
		)
		(pad "D25" smd circle
			(at 7.599934 -9.19988)
			(size 0.3556 0.3556)
			(layers "F.Cu" "F.Mask" "F.Paste")
			(net "GND")
		)
		(pad "D26" smd circle
			(at 8.400034 -9.19988)
			(size 0.3556 0.3556)
			(layers "F.Cu" "F.Mask" "F.Paste")
			(net "P1V8_C")
		)
		(pad "D27" smd circle
			(at 9.19988 -9.19988)
			(size 0.3556 0.3556)
			(layers "F.Cu" "F.Mask" "F.Paste")
			(net "GND")
		)
		(pad "D28" smd circle
			(at 9.99998 -9.19988)
			(size 0.3556 0.3556)
			(layers "F.Cu" "F.Mask" "F.Paste")
			(net "XM_ADDR_9")
		)
		(pad "D29" smd circle
			(at 10.80008 -9.19988)
			(size 0.3556 0.3556)
			(layers "F.Cu" "F.Mask" "F.Paste")
			(net "XM_ADDR_10")
		)
		(pad "D30" smd circle
			(at 11.599926 -9.19988)
			(size 0.3556 0.3556)
			(layers "F.Cu" "F.Mask" "F.Paste")
			(net "XM_ADDR_17")
		)
		(pad "E1" smd circle
			(at -11.599926 -8.400034)
			(size 0.3556 0.3556)
			(layers "F.Cu" "F.Mask" "F.Paste")
			(net "Net_1198")
		)
		(pad "E2" smd circle
			(at -10.80008 -8.400034)
			(size 0.3556 0.3556)
			(layers "F.Cu" "F.Mask" "F.Paste")
			(net "Net_1173")
		)
		(pad "E3" smd circle
			(at -9.99998 -8.400034)
			(size 0.3556 0.3556)
			(layers "F.Cu" "F.Mask" "F.Paste")
			(net "GND")
		)
		(pad "E4" smd circle
			(at -9.19988 -8.400034)
			(size 0.3556 0.3556)
			(layers "F.Cu" "F.Mask" "F.Paste")
			(net "GND")
		)
		(pad "E5" smd circle
			(at -8.400034 -8.400034)
			(size 0.3556 0.3556)
			(layers "F.Cu" "F.Mask" "F.Paste")
			(net "P1V8_C")
		)
		(pad "E6" smd circle
			(at -7.599934 -8.400034)
			(size 0.3556 0.3556)
			(layers "F.Cu" "F.Mask" "F.Paste")
			(net "GND")
		)
		(pad "E7" smd circle
			(at -6.800088 -8.400034)
			(size 0.3556 0.3556)
			(layers "F.Cu" "F.Mask" "F.Paste")
			(net "P1V8_C")
		)
		(pad "E8" smd circle
			(at -5.999988 -8.400034)
			(size 0.3556 0.3556)
			(layers "F.Cu" "F.Mask" "F.Paste")
			(net "GND")
		)
		(pad "E9" smd circle
			(at -5.199888 -8.400034)
			(size 0.3556 0.3556)
			(layers "F.Cu" "F.Mask" "F.Paste")
			(net "P1V8_C")
		)
		(pad "E10" smd circle
			(at -4.400042 -8.400034)
			(size 0.3556 0.3556)
			(layers "F.Cu" "F.Mask" "F.Paste")
			(net "GND")
		)
		(pad "E11" smd circle
			(at -3.599942 -8.400034)
			(size 0.3556 0.3556)
			(layers "F.Cu" "F.Mask" "F.Paste")
			(net "GND")
		)
		(pad "E12" smd circle
			(at -2.800096 -8.400034)
			(size 0.3556 0.3556)
			(layers "F.Cu" "F.Mask" "F.Paste")
			(net "GND")
		)
		(pad "E13" smd circle
			(at -1.999996 -8.400034)
			(size 0.3556 0.3556)
			(layers "F.Cu" "F.Mask" "F.Paste")
			(net "GND")
		)
		(pad "E14" smd circle
			(at -1.199896 -8.400034)
			(size 0.3556 0.3556)
			(layers "F.Cu" "F.Mask" "F.Paste")
			(net "GND")
		)
		(pad "E15" smd circle
			(at -0.40005 -8.400034)
			(size 0.3556 0.3556)
			(layers "F.Cu" "F.Mask" "F.Paste")
			(net "P1V8_C")
		)
		(pad "E16" smd circle
			(at 0.40005 -8.400034)
			(size 0.3556 0.3556)
			(layers "F.Cu" "F.Mask" "F.Paste")
			(net "GND")
		)
		(pad "E17" smd circle
			(at 1.199896 -8.400034)
			(size 0.3556 0.3556)
			(layers "F.Cu" "F.Mask" "F.Paste")
			(net "P1V8_C")
		)
		(pad "E18" smd circle
			(at 1.999996 -8.400034)
			(size 0.3556 0.3556)
			(layers "F.Cu" "F.Mask" "F.Paste")
			(net "GND")
		)
		(pad "E19" smd circle
			(at 2.800096 -8.400034)
			(size 0.3556 0.3556)
			(layers "F.Cu" "F.Mask" "F.Paste")
			(net "P1V8_C")
		)
		(pad "E20" smd circle
			(at 3.599942 -8.400034)
			(size 0.3556 0.3556)
			(layers "F.Cu" "F.Mask" "F.Paste")
			(net "GND")
		)
		(pad "E21" smd circle
			(at 4.400042 -8.400034)
			(size 0.3556 0.3556)
			(layers "F.Cu" "F.Mask" "F.Paste")
			(net "P1V8_C")
		)
		(pad "E22" smd circle
			(at 5.199888 -8.400034)
			(size 0.3556 0.3556)
			(layers "F.Cu" "F.Mask" "F.Paste")
			(net "GND")
		)
		(pad "E23" smd circle
			(at 5.999988 -8.400034)
			(size 0.3556 0.3556)
			(layers "F.Cu" "F.Mask" "F.Paste")
			(net "P1V8_C")
		)
		(pad "E24" smd circle
			(at 6.800088 -8.400034)
			(size 0.3556 0.3556)
			(layers "F.Cu" "F.Mask" "F.Paste")
			(net "GND")
		)
		(pad "E25" smd circle
			(at 7.599934 -8.400034)
			(size 0.3556 0.3556)
			(layers "F.Cu" "F.Mask" "F.Paste")
			(net "P1V8_C")
		)
		(pad "E26" smd circle
			(at 8.400034 -8.400034)
			(size 0.3556 0.3556)
			(layers "F.Cu" "F.Mask" "F.Paste")
			(net "GND")
		)
		(pad "E27" smd circle
			(at 9.19988 -8.400034)
			(size 0.3556 0.3556)
			(layers "F.Cu" "F.Mask" "F.Paste")
			(net "P1V8_C")
		)
		(pad "E28" smd circle
			(at 9.99998 -8.400034)
			(size 0.3556 0.3556)
			(layers "F.Cu" "F.Mask" "F.Paste")
			(net "XM_ADDR_12")
		)
		(pad "E29" smd circle
			(at 10.80008 -8.400034)
			(size 0.3556 0.3556)
			(layers "F.Cu" "F.Mask" "F.Paste")
			(net "XM_DATA_14")
		)
		(pad "E30" smd circle
			(at 11.599926 -8.400034)
			(size 0.3556 0.3556)
			(layers "F.Cu" "F.Mask" "F.Paste")
			(net "XM_ADDR_14")
		)
		(pad "F1" smd circle
			(at -11.599926 -7.599934)
			(size 0.3556 0.3556)
			(layers "F.Cu" "F.Mask" "F.Paste")
			(net "Net_1199")
		)
		(pad "F2" smd circle
			(at -10.80008 -7.599934)
			(size 0.3556 0.3556)
			(layers "F.Cu" "F.Mask" "F.Paste")
			(net "Net_1174")
		)
		(pad "F3" smd circle
			(at -9.99998 -7.599934)
			(size 0.3556 0.3556)
			(layers "F.Cu" "F.Mask" "F.Paste")
			(net "Net_1175")
		)
		(pad "F4" smd circle
			(at -9.19988 -7.599934)
			(size 0.3556 0.3556)
			(layers "F.Cu" "F.Mask" "F.Paste")
			(net "P1V8_C")
		)
		(pad "F5" smd circle
			(at -8.400034 -7.599934)
			(size 0.3556 0.3556)
			(layers "F.Cu" "F.Mask" "F.Paste")
			(net "GND")
		)
		(pad "F6" smd circle
			(at -7.599934 -7.599934)
			(size 0.3556 0.3556)
			(layers "F.Cu" "F.Mask" "F.Paste")
			(net "Net_1176")
		)
		(pad "F7" smd circle
			(at -6.800088 -7.599934)
			(size 0.3556 0.3556)
			(layers "F.Cu" "F.Mask" "F.Paste")
			(net "Net_1177")
		)
		(pad "F8" smd circle
			(at -5.999988 -7.599934)
			(size 0.3556 0.3556)
			(layers "F.Cu" "F.Mask" "F.Paste")
			(net "Net_1178")
		)
		(pad "F9" smd circle
			(at -5.199888 -7.599934)
			(size 0.3556 0.3556)
			(layers "F.Cu" "F.Mask" "F.Paste")
			(net "Net_1179")
		)
		(pad "F10" smd circle
			(at -4.400042 -7.599934)
			(size 0.3556 0.3556)
			(layers "F.Cu" "F.Mask" "F.Paste")
			(net "Net_1180")
		)
		(pad "F11" smd circle
			(at -3.599942 -7.599934)
			(size 0.3556 0.3556)
			(layers "F.Cu" "F.Mask" "F.Paste")
			(net "GND")
		)
		(pad "F12" smd circle
			(at -2.800096 -7.599934)
			(size 0.3556 0.3556)
			(layers "F.Cu" "F.Mask" "F.Paste")
			(net "GND")
		)
		(pad "F13" smd circle
			(at -1.999996 -7.599934)
			(size 0.3556 0.3556)
			(layers "F.Cu" "F.Mask" "F.Paste")
			(net "GND")
		)
		(pad "F14" smd circle
			(at -1.199896 -7.599934)
			(size 0.3556 0.3556)
			(layers "F.Cu" "F.Mask" "F.Paste")
			(net "GND")
		)
		(pad "F15" smd circle
			(at -0.40005 -7.599934)
			(size 0.3556 0.3556)
			(layers "F.Cu" "F.Mask" "F.Paste")
			(net "GND")
		)
		(pad "F16" smd circle
			(at 0.40005 -7.599934)
			(size 0.3556 0.3556)
			(layers "F.Cu" "F.Mask" "F.Paste")
			(net "GND")
		)
		(pad "F17" smd circle
			(at 1.199896 -7.599934)
			(size 0.3556 0.3556)
			(layers "F.Cu" "F.Mask" "F.Paste")
			(net "GND")
		)
		(pad "F18" smd circle
			(at 1.999996 -7.599934)
			(size 0.3556 0.3556)
			(layers "F.Cu" "F.Mask" "F.Paste")
			(net "GND")
		)
		(pad "F19" smd circle
			(at 2.800096 -7.599934)
			(size 0.3556 0.3556)
			(layers "F.Cu" "F.Mask" "F.Paste")
			(net "GND")
		)
		(pad "F20" smd circle
			(at 3.599942 -7.599934)
			(size 0.3556 0.3556)
			(layers "F.Cu" "F.Mask" "F.Paste")
			(net "GND")
		)
		(pad "F21" smd circle
			(at 4.400042 -7.599934)
			(size 0.3556 0.3556)
			(layers "F.Cu" "F.Mask" "F.Paste")
			(net "GND")
		)
		(pad "F22" smd circle
			(at 5.199888 -7.599934)
			(size 0.3556 0.3556)
			(layers "F.Cu" "F.Mask" "F.Paste")
			(net "GND")
		)
		(pad "F23" smd circle
			(at 5.999988 -7.599934)
			(size 0.3556 0.3556)
			(layers "F.Cu" "F.Mask" "F.Paste")
			(net "GND")
		)
		(pad "F24" smd circle
			(at 6.800088 -7.599934)
			(size 0.3556 0.3556)
			(layers "F.Cu" "F.Mask" "F.Paste")
			(net "GND")
		)
		(pad "F25" smd circle
			(at 7.599934 -7.599934)
			(size 0.3556 0.3556)
			(layers "F.Cu" "F.Mask" "F.Paste")
			(net "GND")
		)
		(pad "F26" smd circle
			(at 8.400034 -7.599934)
			(size 0.3556 0.3556)
			(layers "F.Cu" "F.Mask" "F.Paste")
			(net "P1V8_C")
		)
		(pad "F27" smd circle
			(at 9.19988 -7.599934)
			(size 0.3556 0.3556)
			(layers "F.Cu" "F.Mask" "F.Paste")
			(net "GND")
		)
		(pad "F28" smd circle
			(at 9.99998 -7.599934)
			(size 0.3556 0.3556)
			(layers "F.Cu" "F.Mask" "F.Paste")
			(net "XM_ADDR_19")
		)
		(pad "F29" smd circle
			(at 10.80008 -7.599934)
			(size 0.3556 0.3556)
			(layers "F.Cu" "F.Mask" "F.Paste")
			(net "XM_ADDR_16")
		)
		(pad "F30" smd circle
			(at 11.599926 -7.599934)
			(size 0.3556 0.3556)
			(layers "F.Cu" "F.Mask" "F.Paste")
			(net "XM_ADDR_20")
		)
		(pad "G1" smd circle
			(at -11.599926 -6.800088)
			(size 0.3556 0.3556)
			(layers "F.Cu" "F.Mask" "F.Paste")
			(net "Net_1200")
		)
	)
)
